# T6G (Grand Teton) — schematic netlist excerpt (pin names and nets, part order shuffled) for the footprints in the layout excerpt that follows; sources: Cadence DE-HDL packaged netlist, KiCad conversion of 04192023_DAF0TMB3IC0_F0TG_MB_C_brd_V02_OCP.brd

R3866  Q_RES  0 5% EMPTY  pkg 0402LF  page 257 : A = P12V_OCP_SFF_ISENSE_MPS_TIC ; B = P12V_OCP_SFF_ISENSE_TIC
R1280  Q_RES  33 5% CHIP  pkg 0402LF  page 81 : A = FM_P0_PCC0_N ; B = FM_P0_PCC0_R_N

(kicad_pcb
	(version 20260206)
	(generator "pcbnew")
	(generator_version "10.0")
	(general
		(thickness 1.6)
		(legacy_teardrops no)
	)
	(paper "A4")
	(title_block
		(title "04192023_DAF0TMB3IC0_F0TG_MB_C_brd_V02_OCP.brd")
		(comment 1 "Grand Teton / footprints 173-175 of 8354")
	)
	(layers
		(0 "F.Cu" signal "TOP")
		(4 "In1.Cu" signal "GND")
		(6 "In2.Cu" signal "IN1")
		(8 "In3.Cu" signal "GND1")
		(10 "In4.Cu" signal "IN2")
		(12 "In5.Cu" signal "GND2")
		(14 "In6.Cu" signal "IN3")
		(16 "In7.Cu" signal "GND3")
		(18 "In8.Cu" signal "VCC")
		(20 "In9.Cu" signal "VCC1")
		(22 "In10.Cu" signal "GND4")
		(24 "In11.Cu" signal "IN4")
		(26 "In12.Cu" signal "GND5")
		(28 "In13.Cu" signal "IN5")
		(30 "In14.Cu" signal "GND6")
		(32 "In15.Cu" signal "IN6")
		(34 "In16.Cu" signal "GND7")
		(2 "B.Cu" signal "BOTTOM")
		(9 "F.Adhes" user "F.Adhesive")
		(11 "B.Adhes" user "B.Adhesive")
		(13 "F.Paste" user "Package Geometry/Pastemask Top")
		(15 "B.Paste" user "Package Geometry/Pastemask Bottom")
		(5 "F.SilkS" user "Ref Des/Silkscreen Top")
		(7 "B.SilkS" user "Ref Des/Silkscreen Bottom")
		(1 "F.Mask" user "Board Geometry/Soldermask Top")
		(3 "B.Mask" user "Board Geometry/Soldermask Bottom")
		(17 "Dwgs.User" user "User.Drawings")
		(19 "Cmts.User" user "User.Comments")
		(21 "Eco1.User" user "User.Eco1")
		(23 "Eco2.User" user "User.Eco2")
		(25 "Edge.Cuts" user "Board Geometry/Outline")
		(27 "Margin" user)
		(31 "F.CrtYd" user "Package Geometry/Place Bound Top")
		(29 "B.CrtYd" user "Package Geometry/Place Bound Bottom")
		(35 "F.Fab" user "Ref Des/Assembly Top")
		(33 "B.Fab" user "Ref Des/Assembly Bottom")
	)
	(footprint ""
		(layer "F.Cu")
		(at 184.023 -137.632948 -90)
		(property "Reference" "R1280"
			(at 0 0 270)
			(layer "F.SilkS")
			(hide yes)
			(effects
				(font
					(size 1.27 1.27)
				)
			)
		)
		(property "Value" ""
			(at 0 0 270)
			(layer "F.Fab")
			(effects
				(font
					(size 1.27 1.27)
				)
			)
		)
		(duplicate_pad_numbers_are_jumpers no)
		(fp_line
			(start -0.7874 0.4064)
			(end -0.7874 -0.4064)
			(stroke
				(width 0.1524)
				(type default)
			)
			(layer "F.SilkS")
		)
		(fp_line
			(start 0.7874 0.4064)
			(end -0.7874 0.4064)
			(stroke
				(width 0.1524)
				(type default)
			)
			(layer "F.SilkS")
		)
		(fp_line
			(start -0.7874 -0.4064)
			(end 0.7874 -0.4064)
			(stroke
				(width 0.1524)
				(type default)
			)
			(layer "F.SilkS")
		)
		(fp_line
			(start 0.7874 -0.4064)
			(end 0.7874 0.4064)
			(stroke
				(width 0.1524)
				(type default)
			)
			(layer "F.SilkS")
		)
		(fp_line
			(start -0.67945 0.3048)
			(end -0.67945 -0.305054)
			(stroke
				(width 0.1)
				(type default)
			)
			(layer "F.Fab")
		)
		(fp_line
			(start -0.12065 0.3048)
			(end -0.67945 0.3048)
			(stroke
				(width 0.1)
				(type default)
			)
			(layer "F.Fab")
		)
		(fp_line
			(start 0.120396 0.3048)
			(end 0.120396 0.2794)
			(stroke
				(width 0.1)
				(type default)
			)
			(layer "F.Fab")
		)
		(fp_line
			(start 0.67945 0.3048)
			(end 0.120396 0.3048)
			(stroke
				(width 0.1)
				(type default)
			)
			(layer "F.Fab")
		)
		(fp_line
			(start -0.12065 0.2794)
			(end -0.12065 0.3048)
			(stroke
				(width 0.1)
				(type default)
			)
			(layer "F.Fab")
		)
		(fp_line
			(start 0.120396 0.2794)
			(end -0.12065 0.2794)
			(stroke
				(width 0.1)
				(type default)
			)
			(layer "F.Fab")
		)
		(fp_line
			(start -0.12065 -0.2794)
			(end 0.12065 -0.2794)
			(stroke
				(width 0.1)
				(type default)
			)
			(layer "F.Fab")
		)
		(fp_line
			(start 0.12065 -0.2794)
			(end 0.12065 -0.3048)
			(stroke
				(width 0.1)
				(type default)
			)
			(layer "F.Fab")
		)
		(fp_line
			(start 0.12065 -0.3048)
			(end 0.67945 -0.3048)
			(stroke
				(width 0.1)
				(type default)
			)
			(layer "F.Fab")
		)
		(fp_line
			(start 0.67945 -0.3048)
			(end 0.67945 0.3048)
			(stroke
				(width 0.1)
				(type default)
			)
			(layer "F.Fab")
		)
		(fp_line
			(start -0.67945 -0.305054)
			(end -0.12065 -0.305054)
			(stroke
				(width 0.1)
				(type default)
			)
			(layer "F.Fab")
		)
		(fp_line
			(start -0.12065 -0.305054)
			(end -0.12065 -0.2794)
			(stroke
				(width 0.1)
				(type default)
			)
			(layer "F.Fab")
		)
		(pad "1" smd circle
			(at -0.40005 0 270)
			(size 0 0)
			(layers "F.Cu" "F.Mask" "F.Paste")
			(net "FM_P0_PCC0_N")
		)
		(pad "2" smd circle
			(at 0.40005 0 270)
			(size 0 0)
			(layers "F.Cu" "F.Mask" "F.Paste")
			(net "FM_P0_PCC0_R_N")
		)
	)
	(footprint ""
		(layer "F.Cu")
		(at 45.907706 19.444716 -90)
		(property "Reference" "JP6000_23"
			(at 0 0 270)
			(layer "F.SilkS")
			(hide yes)
			(effects
				(font
					(size 1.27 1.27)
				)
			)
		)
		(property "Value" ""
			(at 0 0 270)
			(layer "F.Fab")
			(effects
				(font
					(size 1.27 1.27)
				)
			)
		)
		(duplicate_pad_numbers_are_jumpers no)
		(pad "1" smd circle
			(at 0 0 270)
			(size 0.762 0.762)
			(layers "F.Cu" "F.Mask" "F.Paste")
			(net "Net_10792")
		)
	)
	(footprint ""
		(layer "F.Cu")
		(at 322.837048 -45.86351)
		(property "Reference" "R3866"
			(at 0 0 0)
			(layer "F.SilkS")
			(hide yes)
			(effects
				(font
					(size 1.27 1.27)
				)
			)
		)
		(property "Value" ""
			(at 0 0 0)
			(layer "F.Fab")
			(effects
				(font
					(size 1.27 1.27)
				)
			)
		)
		(duplicate_pad_numbers_are_jumpers no)
		(fp_line
			(start -0.7874 -0.4064)
			(end 0.7874 -0.4064)
			(stroke
				(width 0.1524)
				(type default)
			)
			(layer "F.SilkS")
		)
		(fp_line
			(start -0.7874 0.4064)
			(end -0.7874 -0.4064)
			(stroke
				(width 0.1524)
				(type default)
			)
			(layer "F.SilkS")
		)
		(fp_line
			(start 0.7874 -0.4064)
			(end 0.7874 0.4064)
			(stroke
				(width 0.1524)
				(type default)
			)
			(layer "F.SilkS")
		)
		(fp_line
			(start 0.7874 0.4064)
			(end -0.7874 0.4064)
			(stroke
				(width 0.1524)
				(type default)
			)
			(layer "F.SilkS")
		)
		(fp_line
			(start -0.67945 -0.305054)
			(end -0.12065 -0.305054)
			(stroke
				(width 0.1)
				(type default)
			)
			(layer "F.Fab")
		)
		(fp_line
			(start -0.67945 0.3048)
			(end -0.67945 -0.305054)
			(stroke
				(width 0.1)
				(type default)
			)
			(layer "F.Fab")
		)
		(fp_line
			(start -0.12065 -0.305054)
			(end -0.12065 -0.2794)
			(stroke
				(width 0.1)
				(type default)
			)
			(layer "F.Fab")
		)
		(fp_line
			(start -0.12065 -0.2794)
			(end 0.12065 -0.2794)
			(stroke
				(width 0.1)
				(type default)
			)
			(layer "F.Fab")
		)
		(fp_line
			(start -0.12065 0.2794)
			(end -0.12065 0.3048)
			(stroke
				(width 0.1)
				(type default)
			)
			(layer "F.Fab")
		)
		(fp_line
			(start -0.12065 0.3048)
			(end -0.67945 0.3048)
			(stroke
				(width 0.1)
				(type default)
			)
			(layer "F.Fab")
		)
		(fp_line
			(start 0.120396 0.2794)
			(end -0.12065 0.2794)
			(stroke
				(width 0.1)
				(type default)
			)
			(layer "F.Fab")
		)
		(fp_line
			(start 0.120396 0.3048)
			(end 0.120396 0.2794)
			(stroke
				(width 0.1)
				(type default)
			)
			(layer "F.Fab")
		)
		(fp_line
			(start 0.12065 -0.3048)
			(end 0.67945 -0.3048)
			(stroke
				(width 0.1)
				(type default)
			)
			(layer "F.Fab")
		)
		(fp_line
			(start 0.12065 -0.2794)
			(end 0.12065 -0.3048)
			(stroke
				(width 0.1)
				(type default)
			)
			(layer "F.Fab")
		)
		(fp_line
			(start 0.67945 -0.3048)
			(end 0.67945 0.3048)
			(stroke
				(width 0.1)
				(type default)
			)
			(layer "F.Fab")
		)
		(fp_line
			(start 0.67945 0.3048)
			(end 0.120396 0.3048)
			(stroke
				(width 0.1)
				(type default)
			)
			(layer "F.Fab")
		)
		(pad "1" smd rect
			(at -0.40005 0 180)
			(size 0.4572 0.508)
			(layers "F.Cu" "F.Mask" "F.Paste")
			(net "P12V_OCP_SFF_ISENSE_MPS_TIC")
		)
		(pad "2" smd rect
			(at 0.40005 0 180)
			(size 0.4572 0.508)
			(layers "F.Cu" "F.Mask" "F.Paste")
			(net "P12V_OCP_SFF_ISENSE_TIC")
		)
	)
)
